(kicad_pcb
	(version 20241229)
	(generator "pcbnew")
	(generator_version "9.0")
	(general
		(thickness 1.61)
		(legacy_teardrops no)
	)
	(paper "A3")
	(title_block
		(title "SO-DIMM DDR5 Tester")
		(date "2025-11-26")
		(rev "1.3.0")
		(comment 9 "footprints 152-152 of 627")
	)
	(layers
		(0 "F.Cu" signal)
		(4 "In1.Cu" power)
		(6 "In2.Cu" mixed)
		(8 "In3.Cu" power)
		(10 "In4.Cu" mixed)
		(12 "In5.Cu" power)
		(14 "In6.Cu" mixed)
		(16 "In7.Cu" power)
		(18 "In8.Cu" power)
		(20 "In9.Cu" mixed)
		(22 "In10.Cu" power)
		(2 "B.Cu" signal)
		(9 "F.Adhes" user "F.Adhesive")
		(11 "B.Adhes" user "B.Adhesive")
		(13 "F.Paste" user)
		(15 "B.Paste" user)
		(5 "F.SilkS" user "F.Silkscreen")
		(7 "B.SilkS" user "B.Silkscreen")
		(1 "F.Mask" user)
		(3 "B.Mask" user)
		(17 "Dwgs.User" user "User.Drawings")
		(19 "Cmts.User" user "User.Comments")
		(21 "Eco1.User" user "User.Eco1")
		(23 "Eco2.User" user "User.Eco2")
		(25 "Edge.Cuts" user)
		(27 "Margin" user)
		(31 "F.CrtYd" user "F.Courtyard")
		(29 "B.CrtYd" user "B.Courtyard")
		(35 "F.Fab" user)
		(33 "B.Fab" user)
	)
	(footprint "antmicro-footprints:LGA-33_7x7mm_P0.65mm"
		(layer "F.Cu")
		(at 197.993501 166.8595 -90)
		(property "Reference" "U20"
			(at 4.6405 -1.706499 0)
			(layer "F.SilkS")
			(effects
				(font
					(size 0.7 0.7)
					(thickness 0.15)
				)
				(justify left bottom)
			)
		)
		(property "Value" "MPM54304GMN"
			(at 0 5 270)
			(layer "F.Fab")
			(effects
				(font
					(size 0.7 0.7)
					(thickness 0.15)
				)
				(justify left bottom)
			)
		)
		(property "Datasheet" "https://www.monolithicpower.com/en/documentview/productdocument/index/version/2/document_type/Datasheet/lang/en/sku/MPM54304/document_id/4982/"
			(at 0 0 270)
			(layer "F.Fab")
			(hide yes)
			(effects
				(font
					(size 1.27 1.27)
					(thickness 0.15)
				)
			)
		)
		(property "Author" "Antmicro"
			(at 31.134001 364.853001 0)
			(layer "F.Fab")
			(hide yes)
			(effects
				(font
					(size 1 1)
					(thickness 0.15)
				)
			)
		)
		(property "License" "Apache-2.0"
			(at 31.134001 364.853001 0)
			(layer "F.Fab")
			(hide yes)
			(effects
				(font
					(size 1 1)
					(thickness 0.15)
				)
			)
		)
		(property "MPN" "MPM54304GMN-0000"
			(at 31.134001 364.853001 0)
			(layer "F.Fab")
			(hide yes)
			(effects
				(font
					(size 1 1)
					(thickness 0.15)
				)
			)
		)
		(property "Manufacturer" "Monolithic Power Systems"
			(at 31.134001 364.853001 0)
			(layer "F.Fab")
			(hide yes)
			(effects
				(font
					(size 1 1)
					(thickness 0.15)
				)
			)
		)
		(property ki_fp_filters "CP_48_13_ADI CP_48_13_ADI-M CP_48_13_ADI-L")
		(sheetname "/Supply/")
		(sheetfile "supply.kicad_sch")
		(solder_paste_margin_ratio -0.1)
		(attr smd)
		(fp_line
			(start -3.65 3.648)
			(end -3.65 2.922)
			(stroke
				(width 0.15)
				(type solid)
			)
			(layer "F.SilkS")
		)
		(fp_line
			(start -2.926 3.648)
			(end -3.65 3.648)
			(stroke
				(width 0.15)
				(type solid)
			)
			(layer "F.SilkS")
		)
		(fp_line
			(start 2.922 3.648)
			(end 3.648 3.648)
			(stroke
				(width 0.15)
				(type solid)
			)
			(layer "F.SilkS")
		)
		(fp_line
			(start 3.648 3.648)
			(end 3.648 2.922)
			(stroke
				(width 0.15)
				(type solid)
			)
			(layer "F.SilkS")
		)
		(fp_line
			(start -3.665 -2.928)
			(end -3.665 -3.653)
			(stroke
				(width 0.15)
				(type solid)
			)
			(layer "F.SilkS")
		)
		(fp_line
			(start 2.922 -3.65)
			(end 3.648 -3.65)
			(stroke
				(width 0.15)
				(type solid)
			)
			(layer "F.SilkS")
		)
		(fp_line
			(start 3.648 -3.65)
			(end 3.648 -2.926)
			(stroke
				(width 0.15)
				(type solid)
			)
			(layer "F.SilkS")
		)
		(fp_line
			(start -3.665 -3.653)
			(end -2.94 -3.653)
			(stroke
				(width 0.15)
				(type solid)
			)
			(layer "F.SilkS")
		)
		(fp_circle
			(center -3.8 -1.925)
			(end -3.75 -1.925)
			(stroke
				(width 0.15)
				(type solid)
			)
			(fill yes)
			(layer "F.SilkS")
		)
		(fp_rect
			(start -4 -4)
			(end 3.999 3.999)
			(stroke
				(width 0.05)
				(type solid)
			)
			(fill no)
			(layer "F.CrtYd")
		)
		(fp_line
			(start -3.5 3.499)
			(end 3.499 3.499)
			(stroke
				(width 0.15)
				(type solid)
			)
			(layer "F.Fab")
		)
		(fp_line
			(start 3.499 3.499)
			(end 3.499 -3.5)
			(stroke
				(width 0.15)
				(type solid)
			)
			(layer "F.Fab")
		)
		(fp_line
			(start -3.5 -3.5)
			(end -3.5 3.499)
			(stroke
				(width 0.15)
				(type solid)
			)
			(layer "F.Fab")
		)
		(fp_line
			(start -3.101 -3.5)
			(end -3.5 -3.101)
			(stroke
				(width 0.15)
				(type solid)
			)
			(layer "F.Fab")
		)
		(fp_line
			(start 3.499 -3.5)
			(end -3.5 -3.5)
			(stroke
				(width 0.15)
				(type solid)
			)
			(layer "F.Fab")
		)
		(pad "1" smd rect
			(at -3.138 -1.625)
			(size 0.3 1.125)
			(layers "F.Cu" "F.Mask" "F.Paste")
			(net 53 "/Supply/1V1_local")
			(pinfunction "VOUT3")
			(pintype "power_out")
		)
		(pad "2" smd rect
			(at -3.138 -0.975)
			(size 0.3 1.125)
			(layers "F.Cu" "F.Mask" "F.Paste")
			(net 1 "GND")
			(pinfunction "GND")
			(pintype "passive")
		)
		(pad "3" smd rect
			(at -3.138 -0.328)
			(size 0.3 1.125)
			(layers "F.Cu" "F.Mask" "F.Paste")
			(net 690 "/I^{2}C/PWR.SDA")
			(pinfunction "SDA")
			(pintype "bidirectional")
		)
		(pad "4" smd rect
			(at -3.138 0.325)
			(size 0.3 1.125)
			(layers "F.Cu" "F.Mask" "F.Paste")
			(net 285 "/Supply/QDCDC2_SCL")
			(pinfunction "SCL")
			(pintype "input")
		)
		(pad "5" smd rect
			(at -3.138 0.972)
			(size 0.3 1.125)
			(layers "F.Cu" "F.Mask" "F.Paste")
			(net 1 "GND")
			(pinfunction "GND")
			(pintype "passive")
		)
		(pad "6" smd rect
			(at -3.138 1.624)
			(size 0.3 1.125)
			(layers "F.Cu" "F.Mask" "F.Paste")
			(net 208 "/Supply/FB6")
			(pinfunction "FB2")
			(pintype "input")
		)
		(pad "7" smd rect
			(at -2.926 3.136 90)
			(size 0.3 1.125)
			(layers "F.Cu" "F.Mask" "F.Paste")
			(net 1 "GND")
			(pinfunction "GND")
			(pintype "passive")
		)
		(pad "8" smd rect
			(at -2.275 3.136 90)
			(size 0.3 1.125)
			(layers "F.Cu" "F.Mask" "F.Paste")
			(net 60 "/Supply/5V_local")
			(pinfunction "VOUT2")
			(pintype "power_out")
		)
		(pad "9" smd rect
			(at -1.625 3.136 270)
			(size 0.3 1.125)
			(layers "F.Cu" "F.Mask" "F.Paste")
			(net 60 "/Supply/5V_local")
			(pinfunction "VOUT2")
			(pintype "passive")
		)
		(pad "10" smd rect
			(at -0.975 3.136 270)
			(size 0.3 1.125)
			(layers "F.Cu" "F.Mask" "F.Paste")
			(net 1 "GND")
			(pinfunction "GND")
			(pintype "passive")
		)
		(pad "11" smd rect
			(at -0.328 3.136 270)
			(size 0.3 1.125)
			(layers "F.Cu" "F.Mask" "F.Paste")
			(net 728 "unconnected-(U20-SW2-Pad11)")
			(pinfunction "SW2")
			(pintype "power_out+no_connect")
		)
		(pad "12" smd rect
			(at 0.325 3.136 270)
			(size 0.3 1.125)
			(layers "F.Cu" "F.Mask" "F.Paste")
			(net 729 "unconnected-(U20-SW1-Pad12)")
			(pinfunction "SW1")
			(pintype "power_out+no_connect")
		)
		(pad "13" smd rect
			(at 0.972 3.136 270)
			(size 0.3 1.125)
			(layers "F.Cu" "F.Mask" "F.Paste")
			(net 1 "GND")
			(pinfunction "GND")
			(pintype "passive")
		)
		(pad "14" smd rect
			(at 1.624 3.136 270)
			(size 0.3 1.125)
			(layers "F.Cu" "F.Mask" "F.Paste")
			(net 52 "/Supply/3V3_local")
			(pinfunction "VOUT1")
			(pintype "power_out")
		)
		(pad "15" smd rect
			(at 2.273 3.136 270)
			(size 0.3 1.125)
			(layers "F.Cu" "F.Mask" "F.Paste")
			(net 52 "/Supply/3V3_local")
			(pinfunction "VOUT1")
			(pintype "passive")
		)
		(pad "16" smd rect
			(at 2.922 3.136 270)
			(size 0.3 1.125)
			(layers "F.Cu" "F.Mask" "F.Paste")
			(net 1 "GND")
			(pinfunction "GND")
			(pintype "passive")
		)
		(pad "17" smd rect
			(at 3.136 1.624)
			(size 0.3 1.125)
			(layers "F.Cu" "F.Mask" "F.Paste")
			(net 1 "GND")
			(pinfunction "SGND1")
			(pintype "power_out")
		)
		(pad "18" smd rect
			(at 3.136 0.972)
			(size 0.3 1.125)
			(layers "F.Cu" "F.Mask" "F.Paste")
			(net 209 "/Supply/FB5")
			(pinfunction "FB1")
			(pintype "input")
		)
		(pad "19" smd rect
			(at 3.136 0.325)
			(size 0.3 1.125)
			(layers "F.Cu" "F.Mask" "F.Paste")
			(net 223 "/Supply/EN3")
			(pinfunction "EN/SYNCI")
			(pintype "input")
		)
		(pad "20" smd rect
			(at 3.136 -0.328)
			(size 0.3 1.125)
			(layers "F.Cu" "F.Mask" "F.Paste")
			(net 1 "GND")
			(pinfunction "GND")
			(pintype "passive")
		)
		(pad "21" smd rect
			(at 3.136 -0.975)
			(size 0.3 1.125)
			(layers "F.Cu" "F.Mask" "F.Paste")
			(net 1 "GND")
			(pinfunction "GND")
			(pintype "passive")
		)
		(pad "22" smd rect
			(at 3.136 -1.625)
			(size 0.3 1.125)
			(layers "F.Cu" "F.Mask" "F.Paste")
			(net 56 "/Supply/1V2_local")
			(pinfunction "VOUT4")
			(pintype "power_out")
		)
		(pad "23" smd rect
			(at 2.922 -3.138 90)
			(size 0.3 1.125)
			(layers "F.Cu" "F.Mask" "F.Paste")
			(net 56 "/Supply/1V2_local")
			(pinfunction "VOUT4")
			(pintype "passive")
		)
		(pad "24" smd rect
			(at 2.273 -3.138 90)
			(size 0.3 1.125)
			(layers "F.Cu" "F.Mask" "F.Paste")
			(net 218 "/Supply/FB8")
			(pinfunction "FB4")
			(pintype "input")
		)
		(pad "25" smd rect
			(at 1.624 -3.138 270)
			(size 0.3 1.125)
			(layers "F.Cu" "F.Mask" "F.Paste")
			(net 40 "/Supply/QDCDC2_VCC")
			(pinfunction "VCC")
			(pintype "input")
		)
		(pad "26" smd rect
			(at 0.972 -3.138 270)
			(size 0.3 1.125)
			(layers "F.Cu" "F.Mask" "F.Paste")
			(net 282 "/Supply/PG3")
			(pinfunction "GPIO")
			(pintype "input")
		)
		(pad "27" smd rect
			(at 0.325 -3.138 270)
			(size 0.3 1.125)
			(layers "F.Cu" "F.Mask" "F.Paste")
			(net 1 "GND")
			(pinfunction "GND")
			(pintype "passive")
		)
		(pad "28" smd rect
			(at -0.328 -3.138 270)
			(size 0.3 1.125)
			(layers "F.Cu" "F.Mask" "F.Paste")
			(net 38 "VDC")
			(pinfunction "VIN")
			(pintype "input")
		)
		(pad "29" smd rect
			(at -0.975 -3.138 270)
			(size 0.3 1.125)
			(layers "F.Cu" "F.Mask" "F.Paste")
			(net 38 "VDC")
			(pinfunction "VIN")
			(pintype "passive")
		)
		(pad "30" smd rect
			(at -1.625 -3.138 270)
			(size 0.3 1.125)
			(layers "F.Cu" "F.Mask" "F.Paste")
			(net 1 "GND")
			(pinfunction "SGND2")
			(pintype "power_out")
		)
		(pad "31" smd rect
			(at -2.275 -3.138 270)
			(size 0.3 1.125)
			(layers "F.Cu" "F.Mask" "F.Paste")
			(net 217 "/Supply/FB7")
			(pinfunction "FB3")
			(pintype "input")
		)
		(pad "32" smd rect
			(at -2.926 -3.138 270)
			(size 0.3 1.125)
			(layers "F.Cu" "F.Mask" "F.Paste")
			(net 53 "/Supply/1V1_local")
			(pinfunction "VOUT3")
			(pintype "passive")
		)
		(pad "33" smd rect
			(at -0.863 -0.863 270)
			(size 1.725 1.725)
			(layers "F.Cu" "F.Mask" "F.Paste")
			(net 1 "GND")
			(pinfunction "GND")
			(pintype "passive")
			(solder_paste_margin -0.1)
		)
		(pad "33" smd rect
			(at -0.863 0.86 270)
			(size 1.725 1.725)
			(layers "F.Cu" "F.Mask" "F.Paste")
			(net 1 "GND")
			(pinfunction "GND")
			(pintype "passive")
			(solder_paste_margin -0.1)
		)
		(pad "33" smd rect
			(at 0.86 -0.863 270)
			(size 1.725 1.725)
			(layers "F.Cu" "F.Mask" "F.Paste")
			(net 1 "GND")
			(pinfunction "GND")
			(pintype "passive")
			(solder_paste_margin -0.1)
		)
		(pad "33" smd rect
			(at 0.86 0.86 270)
			(size 1.725 1.725)
			(layers "F.Cu" "F.Mask" "F.Paste")
			(net 1 "GND")
			(pinfunction "GND")
			(pintype "passive")
			(solder_paste_margin -0.1)
		)
	)
)
